# T6G (Grand Teton) — schematic netlist excerpt (pin names and nets, part order shuffled) for the footprints in the layout excerpt that follows; sources: Cadence DE-HDL packaged netlist, KiCad conversion of 04192023_DAF0TMB3IC0_F0TG_MB_C_brd_V02_OCP.brd

PC130  Q_CAP  22UF 16V 20% X6S  pkg C0805  page 192 : A = PVDD_33_S5 ; B = GND
C2581  Q_CAP  22UF 4V 20% X6S  pkg C0402  page 70 : A = PVDDCR_SOC_P0 ; B = GND
C261  Q_CAP  10UF 6.3V 20% X6S  pkg C0402  page 323 : A = P0V9_CPU1_RT_2D ; B = GND

(kicad_pcb
	(version 20260206)
	(generator "pcbnew")
	(generator_version "10.0")
	(general
		(thickness 1.6)
		(legacy_teardrops no)
	)
	(paper "A4")
	(title_block
		(title "04192023_DAF0TMB3IC0_F0TG_MB_C_brd_V02_OCP.brd")
		(comment 1 "Grand Teton / footprints 5377-5379 of 8354")
	)
	(layers
		(0 "F.Cu" signal "TOP")
		(4 "In1.Cu" signal "GND")
		(6 "In2.Cu" signal "IN1")
		(8 "In3.Cu" signal "GND1")
		(10 "In4.Cu" signal "IN2")
		(12 "In5.Cu" signal "GND2")
		(14 "In6.Cu" signal "IN3")
		(16 "In7.Cu" signal "GND3")
		(18 "In8.Cu" signal "VCC")
		(20 "In9.Cu" signal "VCC1")
		(22 "In10.Cu" signal "GND4")
		(24 "In11.Cu" signal "IN4")
		(26 "In12.Cu" signal "GND5")
		(28 "In13.Cu" signal "IN5")
		(30 "In14.Cu" signal "GND6")
		(32 "In15.Cu" signal "IN6")
		(34 "In16.Cu" signal "GND7")
		(2 "B.Cu" signal "BOTTOM")
		(9 "F.Adhes" user "F.Adhesive")
		(11 "B.Adhes" user "B.Adhesive")
		(13 "F.Paste" user "Package Geometry/Pastemask Top")
		(15 "B.Paste" user "Package Geometry/Pastemask Bottom")
		(5 "F.SilkS" user "Ref Des/Silkscreen Top")
		(7 "B.SilkS" user "Ref Des/Silkscreen Bottom")
		(1 "F.Mask" user "Board Geometry/Soldermask Top")
		(3 "B.Mask" user "Board Geometry/Soldermask Bottom")
		(17 "Dwgs.User" user "User.Drawings")
		(19 "Cmts.User" user "User.Comments")
		(21 "Eco1.User" user "User.Eco1")
		(23 "Eco2.User" user "User.Eco2")
		(25 "Edge.Cuts" user "Board Geometry/Outline")
		(27 "Margin" user)
		(31 "F.CrtYd" user "Package Geometry/Place Bound Top")
		(29 "B.CrtYd" user "Package Geometry/Place Bound Bottom")
		(35 "F.Fab" user "Ref Des/Assembly Top")
		(33 "B.Fab" user "Ref Des/Assembly Bottom")
	)
	(footprint ""
		(layer "B.Cu")
		(at 349.834454 -261.17931)
		(property "Reference" "C2581"
			(at 0 0 0)
			(layer "B.SilkS")
			(hide yes)
			(effects
				(font
					(size 1.27 1.27)
				)
				(justify mirror)
			)
		)
		(property "Value" ""
			(at 0 0 0)
			(layer "B.Fab")
			(effects
				(font
					(size 1.27 1.27)
				)
				(justify mirror)
			)
		)
		(duplicate_pad_numbers_are_jumpers no)
		(fp_line
			(start -0.7874 -0.4064)
			(end -0.7874 0.4064)
			(stroke
				(width 0.1524)
				(type default)
			)
			(layer "B.SilkS")
		)
		(fp_line
			(start -0.7874 0.4064)
			(end 0.7874 0.4064)
			(stroke
				(width 0.1524)
				(type default)
			)
			(layer "B.SilkS")
		)
		(fp_line
			(start 0.7874 -0.4064)
			(end -0.7874 -0.4064)
			(stroke
				(width 0.1524)
				(type default)
			)
			(layer "B.SilkS")
		)
		(fp_line
			(start 0.7874 0.4064)
			(end 0.7874 -0.4064)
			(stroke
				(width 0.1524)
				(type default)
			)
			(layer "B.SilkS")
		)
		(fp_line
			(start -0.67945 -0.3048)
			(end -0.67945 0.3048)
			(stroke
				(width 0.1)
				(type default)
			)
			(layer "B.Fab")
		)
		(fp_line
			(start -0.67945 0.3048)
			(end -0.120396 0.3048)
			(stroke
				(width 0.1)
				(type default)
			)
			(layer "B.Fab")
		)
		(fp_line
			(start -0.12065 -0.3048)
			(end -0.67945 -0.3048)
			(stroke
				(width 0.1)
				(type default)
			)
			(layer "B.Fab")
		)
		(fp_line
			(start -0.12065 -0.2794)
			(end -0.12065 -0.3048)
			(stroke
				(width 0.1)
				(type default)
			)
			(layer "B.Fab")
		)
		(fp_line
			(start -0.120396 0.2794)
			(end 0.12065 0.2794)
			(stroke
				(width 0.1)
				(type default)
			)
			(layer "B.Fab")
		)
		(fp_line
			(start -0.120396 0.3048)
			(end -0.120396 0.2794)
			(stroke
				(width 0.1)
				(type default)
			)
			(layer "B.Fab")
		)
		(fp_line
			(start 0.12065 -0.305054)
			(end 0.12065 -0.2794)
			(stroke
				(width 0.1)
				(type default)
			)
			(layer "B.Fab")
		)
		(fp_line
			(start 0.12065 -0.2794)
			(end -0.12065 -0.2794)
			(stroke
				(width 0.1)
				(type default)
			)
			(layer "B.Fab")
		)
		(fp_line
			(start 0.12065 0.2794)
			(end 0.12065 0.3048)
			(stroke
				(width 0.1)
				(type default)
			)
			(layer "B.Fab")
		)
		(fp_line
			(start 0.12065 0.3048)
			(end 0.67945 0.3048)
			(stroke
				(width 0.1)
				(type default)
			)
			(layer "B.Fab")
		)
		(fp_line
			(start 0.67945 -0.305054)
			(end 0.12065 -0.305054)
			(stroke
				(width 0.1)
				(type default)
			)
			(layer "B.Fab")
		)
		(fp_line
			(start 0.67945 0.3048)
			(end 0.67945 -0.305054)
			(stroke
				(width 0.1)
				(type default)
			)
			(layer "B.Fab")
		)
		(pad "1" smd circle
			(at 0.40005 0 180)
			(size 0 0)
			(layers "B.Cu" "B.Mask" "B.Paste")
			(net "PVDDCR_SOC_P0")
		)
		(pad "2" smd circle
			(at -0.40005 0 180)
			(size 0 0)
			(layers "B.Cu" "B.Mask" "B.Paste")
			(net "GND")
		)
	)
	(footprint ""
		(layer "B.Cu")
		(at 204.03312 -331.027786 -90)
		(property "Reference" "PC130"
			(at 0 0 90)
			(layer "B.SilkS")
			(hide yes)
			(effects
				(font
					(size 1.27 1.27)
				)
				(justify mirror)
			)
		)
		(property "Value" ""
			(at 0 0 90)
			(layer "B.Fab")
			(effects
				(font
					(size 1.27 1.27)
				)
				(justify mirror)
			)
		)
		(duplicate_pad_numbers_are_jumpers no)
		(fp_line
			(start -1.524 0.762)
			(end 1.524 0.762)
			(stroke
				(width 0.1524)
				(type default)
			)
			(layer "B.SilkS")
		)
		(fp_line
			(start 1.524 0.762)
			(end 1.524 -0.762)
			(stroke
				(width 0.1524)
				(type default)
			)
			(layer "B.SilkS")
		)
		(fp_line
			(start -1.524 -0.762)
			(end -1.524 0.762)
			(stroke
				(width 0.1524)
				(type default)
			)
			(layer "B.SilkS")
		)
		(fp_line
			(start 1.524 -0.762)
			(end -1.524 -0.762)
			(stroke
				(width 0.1524)
				(type default)
			)
			(layer "B.SilkS")
		)
		(fp_line
			(start -1.1049 0.724916)
			(end -1.1049 -0.724916)
			(stroke
				(width 0.1)
				(type default)
			)
			(layer "B.Fab")
		)
		(fp_line
			(start 1.1049 0.724916)
			(end -1.1049 0.724916)
			(stroke
				(width 0.1)
				(type default)
			)
			(layer "B.Fab")
		)
		(fp_line
			(start -1.1049 -0.724916)
			(end 1.1049 -0.724916)
			(stroke
				(width 0.1)
				(type default)
			)
			(layer "B.Fab")
		)
		(fp_line
			(start 1.1049 -0.724916)
			(end 1.1049 0.724916)
			(stroke
				(width 0.1)
				(type default)
			)
			(layer "B.Fab")
		)
		(pad "1" smd rect
			(at 0.889 0 270)
			(size 1.016 1.27)
			(layers "B.Cu" "B.Mask" "B.Paste")
			(net "PVDD_33_S5")
		)
		(pad "2" smd rect
			(at -0.889 0 270)
			(size 1.016 1.27)
			(layers "B.Cu" "B.Mask" "B.Paste")
			(net "GND")
		)
	)
	(footprint ""
		(layer "B.Cu")
		(at 54.591204 -390.560052 90)
		(property "Reference" "C261"
			(at 0 0 90)
			(layer "B.SilkS")
			(hide yes)
			(effects
				(font
					(size 1.27 1.27)
				)
				(justify mirror)
			)
		)
		(property "Value" ""
			(at 0 0 90)
			(layer "B.Fab")
			(effects
				(font
					(size 1.27 1.27)
				)
				(justify mirror)
			)
		)
		(duplicate_pad_numbers_are_jumpers no)
		(fp_line
			(start 0.7874 -0.4064)
			(end -0.7874 -0.4064)
			(stroke
				(width 0.1524)
				(type default)
			)
			(layer "B.SilkS")
		)
		(fp_line
			(start -0.7874 -0.4064)
			(end -0.7874 0.4064)
			(stroke
				(width 0.1524)
				(type default)
			)
			(layer "B.SilkS")
		)
		(fp_line
			(start 0.7874 0.4064)
			(end 0.7874 -0.4064)
			(stroke
				(width 0.1524)
				(type default)
			)
			(layer "B.SilkS")
		)
		(fp_line
			(start -0.7874 0.4064)
			(end 0.7874 0.4064)
			(stroke
				(width 0.1524)
				(type default)
			)
			(layer "B.SilkS")
		)
		(fp_line
			(start 0.67945 -0.305054)
			(end 0.12065 -0.305054)
			(stroke
				(width 0.1)
				(type default)
			)
			(layer "B.Fab")
		)
		(fp_line
			(start 0.12065 -0.305054)
			(end 0.12065 -0.2794)
			(stroke
				(width 0.1)
				(type default)
			)
			(layer "B.Fab")
		)
		(fp_line
			(start -0.12065 -0.3048)
			(end -0.67945 -0.3048)
			(stroke
				(width 0.1)
				(type default)
			)
			(layer "B.Fab")
		)
		(fp_line
			(start -0.67945 -0.3048)
			(end -0.67945 0.3048)
			(stroke
				(width 0.1)
				(type default)
			)
			(layer "B.Fab")
		)
		(fp_line
			(start 0.12065 -0.2794)
			(end -0.12065 -0.2794)
			(stroke
				(width 0.1)
				(type default)
			)
			(layer "B.Fab")
		)
		(fp_line
			(start -0.12065 -0.2794)
			(end -0.12065 -0.3048)
			(stroke
				(width 0.1)
				(type default)
			)
			(layer "B.Fab")
		)
		(fp_line
			(start 0.12065 0.2794)
			(end 0.12065 0.3048)
			(stroke
				(width 0.1)
				(type default)
			)
			(layer "B.Fab")
		)
		(fp_line
			(start -0.120396 0.2794)
			(end 0.12065 0.2794)
			(stroke
				(width 0.1)
				(type default)
			)
			(layer "B.Fab")
		)
		(fp_line
			(start 0.67945 0.3048)
			(end 0.67945 -0.305054)
			(stroke
				(width 0.1)
				(type default)
			)
			(layer "B.Fab")
		)
		(fp_line
			(start 0.12065 0.3048)
			(end 0.67945 0.3048)
			(stroke
				(width 0.1)
				(type default)
			)
			(layer "B.Fab")
		)
		(fp_line
			(start -0.120396 0.3048)
			(end -0.120396 0.2794)
			(stroke
				(width 0.1)
				(type default)
			)
			(layer "B.Fab")
		)
		(fp_line
			(start -0.67945 0.3048)
			(end -0.120396 0.3048)
			(stroke
				(width 0.1)
				(type default)
			)
			(layer "B.Fab")
		)
		(pad "1" smd circle
			(at 0.40005 0 270)
			(size 0 0)
			(layers "B.Cu" "B.Mask" "B.Paste")
			(net "P0V9_CPU1_RT_2D")
		)
		(pad "2" smd circle
			(at -0.40005 0 270)
			(size 0 0)
			(layers "B.Cu" "B.Mask" "B.Paste")
			(net "GND")
		)
	)
)
